# BARRELEYE-G2-SXM2 RISER BOARD-EVT-X00-BOM-X01-20171102_Final.xls.xlsx — POP_GA (bom)
| FOXCONN TECHNOLOGY GROUP |  |  |  |  |  |  |  |  |  |  |  |  |
| BILL OF MATERIAL |  |  |  |  |  |  |  |  |  |  |  |  |
| REV OF  BOM |  | CUSTOMER | <name> |  | CUSTOMER P/N |  | PRODUCT CODE |  | PWA  REV |  | DATE |  |
| Sourcing (Single/Sole/Multi) | Critical Commodity (Y or N) | Component Class (1, 2, other) | Customer PSL (Y or N) | Item Number | Foxconn P/N | Customer P/N | Part Description | Manufacturer  Full Name | Manufacturer  Part Number | Qty | RoHS Status | Location |
